(kicad_pcb
	(version 20260206)
	(generator "pcbnew")
	(generator_version "10.0")
	(general
		(thickness 1.6)
		(legacy_teardrops no)
	)
	(paper "A4")
	(title_block
		(title "baseboard — 13948-1b.1110WZS1818.brd")
		(comment 1 "Honey Badger (Wiwynn) / footprints 1093-1100 of 2523")
	)
	(layers
		(0 "F.Cu" signal "TOP")
		(4 "In1.Cu" signal "L2GND")
		(6 "In2.Cu" signal "L3")
		(8 "In3.Cu" signal "L4VCC")
		(10 "In4.Cu" signal "L5VCC")
		(12 "In5.Cu" signal "L6")
		(14 "In6.Cu" signal "L7GND")
		(2 "B.Cu" signal "BOTTOM")
		(9 "F.Adhes" user "F.Adhesive")
		(11 "B.Adhes" user "B.Adhesive")
		(13 "F.Paste" user "Package Geometry/Pastemask Top")
		(15 "B.Paste" user "Package Geometry/Pastemask Bottom")
		(5 "F.SilkS" user "Ref Des/Silkscreen Top")
		(7 "B.SilkS" user "Ref Des/Silkscreen Bottom")
		(1 "F.Mask" user "Board Geometry/Soldermask Top")
		(3 "B.Mask" user "Board Geometry/Soldermask Bottom")
		(17 "Dwgs.User" user "User.Drawings")
		(19 "Cmts.User" user "User.Comments")
		(21 "Eco1.User" user "User.Eco1")
		(23 "Eco2.User" user "User.Eco2")
		(25 "Edge.Cuts" user "Board Geometry/Outline")
		(27 "Margin" user)
		(31 "F.CrtYd" user "Package Geometry/Place Bound Top")
		(29 "B.CrtYd" user "Package Geometry/Place Bound Bottom")
		(35 "F.Fab" user "Ref Des/Assembly Top")
		(33 "B.Fab" user "Ref Des/Assembly Bottom")
	)
	(footprint ""
		(layer "F.Cu")
		(at 220.091 -26.035)
		(property "Reference" "R7890"
			(at 0 0 0)
			(layer "F.SilkS")
			(hide yes)
			(effects
				(font
					(size 1.27 1.27)
				)
			)
		)
		(property "Value" "0R2J-2-GP"
			(at 0.064008 -3.993896 0)
			(unlocked yes)
			(layer "F.Fab")
			(hide yes)
			(effects
				(font
					(size 1.016 1.016)
					(thickness 0.1524)
				)
			)
		)
		(property "Device Type" "R402H16"
			(at 0.064008 -5.517896 0)
			(unlocked yes)
			(layer "F.Fab")
			(hide yes)
			(effects
				(font
					(size 1.016 1.016)
					(thickness 0.1524)
				)
			)
		)
		(duplicate_pad_numbers_are_jumpers no)
		(fp_line
			(start -0.508 -0.9398)
			(end -0.508 0.9398)
			(stroke
				(width 0.1524)
				(type default)
			)
			(layer "F.SilkS")
		)
		(fp_line
			(start 0.508 -0.9398)
			(end -0.508 -0.9398)
			(stroke
				(width 0.1524)
				(type default)
			)
			(layer "F.SilkS")
		)
		(fp_rect
			(start -0.508 0.9398)
			(end 0.508 -0.9398)
			(stroke
				(width 0)
				(type default)
			)
			(fill no)
			(layer "F.CrtYd")
		)
		(fp_rect
			(start -0.508 0.9398)
			(end 0.508 -0.9398)
			(stroke
				(width 0)
				(type default)
			)
			(fill no)
			(layer "F.Fab")
		)
		(pad "1" smd custom
			(at 0 -0.4445)
			(size 0.1397 0.1397)
			(layers "F.Cu" "F.Mask" "F.Paste")
			(net "PMU_PLTRST_N")
			(options
				(clearance outline)
				(anchor circle)
			)
			(primitives
				(gr_poly
					(pts
						(arc
							(start -0.1778 -0.2794)
							(mid -0.249642 -0.249642)
							(end -0.2794 -0.1778)
						)
						(arc
							(start -0.2794 0.1778)
							(mid -0.249642 0.249642)
							(end -0.1778 0.2794)
						)
						(arc
							(start 0.1778 0.2794)
							(mid 0.249642 0.249642)
							(end 0.2794 0.1778)
						)
						(arc
							(start 0.2794 -0.1778)
							(mid 0.249642 -0.249642)
							(end 0.1778 -0.2794)
						)
					)
					(width 0)
					(fill yes)
				)
			)
		)
		(pad "2" smd custom
			(at 0 0.4445)
			(size 0.1397 0.1397)
			(layers "F.Cu" "F.Mask" "F.Paste")
			(net "BMC_ID_LED_R")
			(options
				(clearance outline)
				(anchor circle)
			)
			(primitives
				(gr_poly
					(pts
						(arc
							(start -0.1778 -0.2794)
							(mid -0.249642 -0.249642)
							(end -0.2794 -0.1778)
						)
						(arc
							(start -0.2794 0.1778)
							(mid -0.249642 0.249642)
							(end -0.1778 0.2794)
						)
						(arc
							(start 0.1778 0.2794)
							(mid 0.249642 0.249642)
							(end 0.2794 0.1778)
						)
						(arc
							(start 0.2794 -0.1778)
							(mid 0.249642 -0.249642)
							(end 0.1778 -0.2794)
						)
					)
					(width 0)
					(fill yes)
				)
			)
		)
	)
	(footprint ""
		(layer "F.Cu")
		(at 258.699 -70.485 -90)
		(property "Reference" "C309"
			(at 0 0 270)
			(layer "F.SilkS")
			(hide yes)
			(effects
				(font
					(size 1.27 1.27)
				)
			)
		)
		(property "Value" "SCD1U25V2KX-2-GP"
			(at 1.1811 -2.7051 270)
			(unlocked yes)
			(layer "F.Fab")
			(hide yes)
			(effects
				(font
					(size 1.016 1.016)
					(thickness 0.1524)
				)
			)
		)
		(property "Device Type" "C402H22"
			(at 1.1811 -4.2291 270)
			(unlocked yes)
			(layer "F.Fab")
			(hide yes)
			(effects
				(font
					(size 1.016 1.016)
					(thickness 0.1524)
				)
			)
		)
		(duplicate_pad_numbers_are_jumpers no)
		(fp_rect
			(start -0.4318 0.9525)
			(end 0.4318 -0.9525)
			(stroke
				(width 0)
				(type default)
			)
			(fill no)
			(layer "F.CrtYd")
		)
		(fp_rect
			(start -0.4318 0.9525)
			(end 0.4318 -0.9525)
			(stroke
				(width 0)
				(type default)
			)
			(fill no)
			(layer "F.Fab")
		)
		(pad "1" smd custom
			(at 0 -0.4445 270)
			(size 0.1524 0.1524)
			(layers "F.Cu" "F.Mask" "F.Paste")
			(net "P12V_MSB")
			(options
				(clearance outline)
				(anchor circle)
			)
			(primitives
				(gr_poly
					(pts
						(arc
							(start 0.3048 -0.2032)
							(mid 0.275042 -0.275042)
							(end 0.2032 -0.3048)
						)
						(arc
							(start -0.2032 -0.3048)
							(mid -0.275042 -0.275042)
							(end -0.3048 -0.2032)
						)
						(arc
							(start -0.3048 0.2032)
							(mid -0.275042 0.275042)
							(end -0.2032 0.3048)
						)
						(arc
							(start 0.2032 0.3048)
							(mid 0.275042 0.275042)
							(end 0.3048 0.2032)
						)
					)
					(width 0)
					(fill yes)
				)
			)
		)
		(pad "2" smd custom
			(at 0 0.4445 270)
			(size 0.1524 0.1524)
			(layers "F.Cu" "F.Mask" "F.Paste")
			(net "GND")
			(options
				(clearance outline)
				(anchor circle)
			)
			(primitives
				(gr_poly
					(pts
						(arc
							(start 0.3048 -0.2032)
							(mid 0.275042 -0.275042)
							(end 0.2032 -0.3048)
						)
						(arc
							(start -0.2032 -0.3048)
							(mid -0.275042 -0.275042)
							(end -0.3048 -0.2032)
						)
						(arc
							(start -0.3048 0.2032)
							(mid -0.275042 0.275042)
							(end -0.2032 0.3048)
						)
						(arc
							(start 0.2032 0.3048)
							(mid 0.275042 0.275042)
							(end 0.3048 0.2032)
						)
					)
					(width 0)
					(fill yes)
				)
			)
		)
	)
	(footprint ""
		(layer "F.Cu")
		(at 119.64797 -74.6252 -90)
		(property "Reference" "SR597"
			(at 0 0 270)
			(layer "F.SilkS")
			(hide yes)
			(effects
				(font
					(size 1.27 1.27)
				)
			)
		)
		(property "Value" "0R2J-2-GP"
			(at 0.064008 -3.993896 270)
			(unlocked yes)
			(layer "F.Fab")
			(hide yes)
			(effects
				(font
					(size 1.016 1.016)
					(thickness 0.1524)
				)
			)
		)
		(property "Device Type" "R402H16"
			(at 0.064008 -5.517896 270)
			(unlocked yes)
			(layer "F.Fab")
			(hide yes)
			(effects
				(font
					(size 1.016 1.016)
					(thickness 0.1524)
				)
			)
		)
		(duplicate_pad_numbers_are_jumpers no)
		(fp_line
			(start -0.508 -0.9398)
			(end -0.508 0.9398)
			(stroke
				(width 0.1524)
				(type default)
			)
			(layer "F.SilkS")
		)
		(fp_line
			(start 0.508 -0.9398)
			(end -0.508 -0.9398)
			(stroke
				(width 0.1524)
				(type default)
			)
			(layer "F.SilkS")
		)
		(fp_rect
			(start -0.508 0.9398)
			(end 0.508 -0.9398)
			(stroke
				(width 0)
				(type default)
			)
			(fill no)
			(layer "F.CrtYd")
		)
		(fp_rect
			(start -0.508 0.9398)
			(end 0.508 -0.9398)
			(stroke
				(width 0)
				(type default)
			)
			(fill no)
			(layer "F.Fab")
		)
		(pad "1" smd custom
			(at 0 -0.4445 270)
			(size 0.1397 0.1397)
			(layers "F.Cu" "F.Mask" "F.Paste")
			(net "EXP_REF_CLK_N_R")
			(options
				(clearance outline)
				(anchor circle)
			)
			(primitives
				(gr_poly
					(pts
						(arc
							(start -0.1778 -0.2794)
							(mid -0.249642 -0.249642)
							(end -0.2794 -0.1778)
						)
						(arc
							(start -0.2794 0.1778)
							(mid -0.249642 0.249642)
							(end -0.1778 0.2794)
						)
						(arc
							(start 0.1778 0.2794)
							(mid 0.249642 0.249642)
							(end 0.2794 0.1778)
						)
						(arc
							(start 0.2794 -0.1778)
							(mid 0.249642 -0.249642)
							(end 0.1778 -0.2794)
						)
					)
					(width 0)
					(fill yes)
				)
			)
		)
		(pad "2" smd custom
			(at 0 0.4445 270)
			(size 0.1397 0.1397)
			(layers "F.Cu" "F.Mask" "F.Paste")
			(net "EXP_REF_CLK_N")
			(options
				(clearance outline)
				(anchor circle)
			)
			(primitives
				(gr_poly
					(pts
						(arc
							(start -0.1778 -0.2794)
							(mid -0.249642 -0.249642)
							(end -0.2794 -0.1778)
						)
						(arc
							(start -0.2794 0.1778)
							(mid -0.249642 0.249642)
							(end -0.1778 0.2794)
						)
						(arc
							(start 0.1778 0.2794)
							(mid 0.249642 0.249642)
							(end 0.2794 0.1778)
						)
						(arc
							(start 0.2794 -0.1778)
							(mid 0.249642 -0.249642)
							(end 0.1778 -0.2794)
						)
					)
					(width 0)
					(fill yes)
				)
			)
		)
	)
	(footprint ""
		(layer "F.Cu")
		(at 307.594 -216.789 180)
		(property "Reference" "R657"
			(at 0 0 180)
			(layer "F.SilkS")
			(hide yes)
			(effects
				(font
					(size 1.27 1.27)
				)
			)
		)
		(property "Value" "4K7R2F-GP"
			(at 0.064008 -3.993896 180)
			(unlocked yes)
			(layer "F.Fab")
			(hide yes)
			(effects
				(font
					(size 1.016 1.016)
					(thickness 0.1524)
				)
			)
		)
		(property "Device Type" "R402H16"
			(at 0.064008 -5.517896 180)
			(unlocked yes)
			(layer "F.Fab")
			(hide yes)
			(effects
				(font
					(size 1.016 1.016)
					(thickness 0.1524)
				)
			)
		)
		(duplicate_pad_numbers_are_jumpers no)
		(fp_line
			(start 0.508 -0.9398)
			(end -0.508 -0.9398)
			(stroke
				(width 0.1524)
				(type default)
			)
			(layer "F.SilkS")
		)
		(fp_line
			(start -0.508 -0.9398)
			(end -0.508 0.9398)
			(stroke
				(width 0.1524)
				(type default)
			)
			(layer "F.SilkS")
		)
		(fp_rect
			(start -0.508 0.9398)
			(end 0.508 -0.9398)
			(stroke
				(width 0)
				(type default)
			)
			(fill no)
			(layer "F.CrtYd")
		)
		(fp_rect
			(start -0.508 0.9398)
			(end 0.508 -0.9398)
			(stroke
				(width 0)
				(type default)
			)
			(fill no)
			(layer "F.Fab")
		)
		(pad "1" smd custom
			(at 0 -0.4445 180)
			(size 0.1397 0.1397)
			(layers "F.Cu" "F.Mask" "F.Paste")
			(net "P3V3_STBY")
			(options
				(clearance outline)
				(anchor circle)
			)
			(primitives
				(gr_poly
					(pts
						(arc
							(start -0.1778 -0.2794)
							(mid -0.249642 -0.249642)
							(end -0.2794 -0.1778)
						)
						(arc
							(start -0.2794 0.1778)
							(mid -0.249642 0.249642)
							(end -0.1778 0.2794)
						)
						(arc
							(start 0.1778 0.2794)
							(mid 0.249642 0.249642)
							(end 0.2794 0.1778)
						)
						(arc
							(start 0.2794 -0.1778)
							(mid 0.249642 -0.249642)
							(end 0.1778 -0.2794)
						)
					)
					(width 0)
					(fill yes)
				)
			)
		)
		(pad "2" smd custom
			(at 0 0.4445 180)
			(size 0.1397 0.1397)
			(layers "F.Cu" "F.Mask" "F.Paste")
			(net "BMC_DEBUG_OE_2_N")
			(options
				(clearance outline)
				(anchor circle)
			)
			(primitives
				(gr_poly
					(pts
						(arc
							(start -0.1778 -0.2794)
							(mid -0.249642 -0.249642)
							(end -0.2794 -0.1778)
						)
						(arc
							(start -0.2794 0.1778)
							(mid -0.249642 0.249642)
							(end -0.1778 0.2794)
						)
						(arc
							(start 0.1778 0.2794)
							(mid 0.249642 0.249642)
							(end 0.2794 0.1778)
						)
						(arc
							(start 0.2794 -0.1778)
							(mid 0.249642 -0.249642)
							(end 0.1778 -0.2794)
						)
					)
					(width 0)
					(fill yes)
				)
			)
		)
	)
	(footprint ""
		(layer "F.Cu")
		(at 103.867966 -63.8556 90)
		(property "Reference" "SC915"
			(at 0 0 90)
			(layer "F.SilkS")
			(hide yes)
			(effects
				(font
					(size 1.27 1.27)
				)
			)
		)
		(property "Value" "SC22U6D3V5MX-2GP"
			(at -0.0762 -6.1214 90)
			(unlocked yes)
			(layer "F.Fab")
			(hide yes)
			(effects
				(font
					(size 1.016 1.016)
					(thickness 0.1524)
				)
			)
		)
		(property "Device Type" "C805H58"
			(at -0.0762 -8.1534 90)
			(unlocked yes)
			(layer "F.Fab")
			(hide yes)
			(effects
				(font
					(size 1.016 1.016)
					(thickness 0.1524)
				)
			)
		)
		(duplicate_pad_numbers_are_jumpers no)
		(fp_line
			(start 0.635 0)
			(end -0.635 0)
			(stroke
				(width 0.508)
				(type default)
			)
			(layer "F.SilkS")
		)
		(fp_rect
			(start -0.9652 1.778)
			(end 0.9652 -1.778)
			(stroke
				(width 0)
				(type default)
			)
			(fill no)
			(layer "F.CrtYd")
		)
		(fp_poly
			(pts
				(xy -0.9652 -1.778) (xy 0.9652 -1.778) (xy 0.9652 1.778) (xy -0.9652 1.778)
			)
			(stroke
				(width 0)
				(type default)
			)
			(fill no)
			(layer "F.Fab")
		)
		(pad "1" smd rect
			(at 0 -0.9652 90)
			(size 1.397 1.143)
			(layers "F.Cu" "F.Mask" "F.Paste")
			(net "HM40ADC_VDDA")
		)
		(pad "2" smd rect
			(at 0 0.9652 90)
			(size 1.397 1.143)
			(layers "F.Cu" "F.Mask" "F.Paste")
			(net "GND")
		)
	)
	(footprint ""
		(layer "F.Cu")
		(at 103.51897 -114.3 180)
		(property "Reference" "SC1087"
			(at 0 0 180)
			(layer "F.SilkS")
			(hide yes)
			(effects
				(font
					(size 1.27 1.27)
				)
			)
		)
		(property "Value" "SCD01U10V1KX-GP"
			(at -2.8321 -1.7399 180)
			(unlocked yes)
			(layer "F.Fab")
			(hide yes)
			(effects
				(font
					(size 1.016 1.016)
					(thickness 0.1524)
				)
			)
		)
		(property "Device Type" "C0201H13"
			(at -2.8321 -3.2639 180)
			(unlocked yes)
			(layer "F.Fab")
			(hide yes)
			(effects
				(font
					(size 1.016 1.016)
					(thickness 0.1524)
				)
			)
		)
		(duplicate_pad_numbers_are_jumpers no)
		(fp_rect
			(start -0.2794 0.6477)
			(end 0.2794 -0.6477)
			(stroke
				(width 0)
				(type default)
			)
			(fill no)
			(layer "F.CrtYd")
		)
		(fp_rect
			(start -0.2794 0.6477)
			(end 0.2794 -0.6477)
			(stroke
				(width 0)
				(type default)
			)
			(fill no)
			(layer "F.Fab")
		)
		(pad "1" smd custom
			(at 0 -0.2794 180)
			(size 0.0762 0.0762)
			(layers "F.Cu" "F.Mask" "F.Paste")
			(net "SAS_HDD_TX10_N")
			(options
				(clearance outline)
				(anchor circle)
			)
			(primitives
				(gr_poly
					(pts
						(arc
							(start 0.1524 -0.127)
							(mid 0.137521 -0.162921)
							(end 0.1016 -0.1778)
						)
						(arc
							(start -0.1016 -0.1778)
							(mid -0.137521 -0.162921)
							(end -0.1524 -0.127)
						)
						(arc
							(start -0.1524 0.127)
							(mid -0.137521 0.162921)
							(end -0.1016 0.1778)
						)
						(arc
							(start 0.1016 0.1778)
							(mid 0.137521 0.162921)
							(end 0.1524 0.127)
						)
					)
					(width 0)
					(fill yes)
				)
			)
		)
		(pad "2" smd custom
			(at 0 0.2794 180)
			(size 0.0762 0.0762)
			(layers "F.Cu" "F.Mask" "F.Paste")
			(net "SAS_EXP_GF_TX_DN14")
			(options
				(clearance outline)
				(anchor circle)
			)
			(primitives
				(gr_poly
					(pts
						(arc
							(start 0.1524 -0.127)
							(mid 0.137521 -0.162921)
							(end 0.1016 -0.1778)
						)
						(arc
							(start -0.1016 -0.1778)
							(mid -0.137521 -0.162921)
							(end -0.1524 -0.127)
						)
						(arc
							(start -0.1524 0.127)
							(mid -0.137521 0.162921)
							(end -0.1016 0.1778)
						)
						(arc
							(start 0.1016 0.1778)
							(mid 0.137521 0.162921)
							(end 0.1524 0.127)
						)
					)
					(width 0)
					(fill yes)
				)
			)
		)
	)
	(footprint ""
		(layer "F.Cu")
		(at 281.051 -212.217)
		(property "Reference" "R125"
			(at 0 0 0)
			(layer "F.SilkS")
			(hide yes)
			(effects
				(font
					(size 1.27 1.27)
				)
			)
		)
		(property "Value" "0R2J-2-GP"
			(at 0.064008 -3.993896 0)
			(unlocked yes)
			(layer "F.Fab")
			(hide yes)
			(effects
				(font
					(size 1.016 1.016)
					(thickness 0.1524)
				)
			)
		)
		(property "Device Type" "R402H16"
			(at 0.064008 -5.517896 0)
			(unlocked yes)
			(layer "F.Fab")
			(hide yes)
			(effects
				(font
					(size 1.016 1.016)
					(thickness 0.1524)
				)
			)
		)
		(duplicate_pad_numbers_are_jumpers no)
		(fp_line
			(start -0.508 -0.9398)
			(end -0.508 0.9398)
			(stroke
				(width 0.1524)
				(type default)
			)
			(layer "F.SilkS")
		)
		(fp_line
			(start 0.508 -0.9398)
			(end -0.508 -0.9398)
			(stroke
				(width 0.1524)
				(type default)
			)
			(layer "F.SilkS")
		)
		(fp_rect
			(start -0.508 0.9398)
			(end 0.508 -0.9398)
			(stroke
				(width 0)
				(type default)
			)
			(fill no)
			(layer "F.CrtYd")
		)
		(fp_rect
			(start -0.508 0.9398)
			(end 0.508 -0.9398)
			(stroke
				(width 0)
				(type default)
			)
			(fill no)
			(layer "F.Fab")
		)
		(pad "1" smd custom
			(at 0 -0.4445)
			(size 0.1397 0.1397)
			(layers "F.Cu" "F.Mask" "F.Paste")
			(net "P1V26_STBY_PG")
			(options
				(clearance outline)
				(anchor circle)
			)
			(primitives
				(gr_poly
					(pts
						(arc
							(start -0.1778 -0.2794)
							(mid -0.249642 -0.249642)
							(end -0.2794 -0.1778)
						)
						(arc
							(start -0.2794 0.1778)
							(mid -0.249642 0.249642)
							(end -0.1778 0.2794)
						)
						(arc
							(start 0.1778 0.2794)
							(mid 0.249642 0.249642)
							(end 0.2794 0.1778)
						)
						(arc
							(start 0.2794 -0.1778)
							(mid 0.249642 -0.249642)
							(end 0.1778 -0.2794)
						)
					)
					(width 0)
					(fill yes)
				)
			)
		)
		(pad "2" smd custom
			(at 0 0.4445)
			(size 0.1397 0.1397)
			(layers "F.Cu" "F.Mask" "F.Paste")
			(net "FM_BMC_RESET_N")
			(options
				(clearance outline)
				(anchor circle)
			)
			(primitives
				(gr_poly
					(pts
						(arc
							(start -0.1778 -0.2794)
							(mid -0.249642 -0.249642)
							(end -0.2794 -0.1778)
						)
						(arc
							(start -0.2794 0.1778)
							(mid -0.249642 0.249642)
							(end -0.1778 0.2794)
						)
						(arc
							(start 0.1778 0.2794)
							(mid 0.249642 0.249642)
							(end 0.2794 0.1778)
						)
						(arc
							(start 0.2794 -0.1778)
							(mid 0.249642 -0.249642)
							(end 0.1778 -0.2794)
						)
					)
					(width 0)
					(fill yes)
				)
			)
		)
	)
	(footprint ""
		(layer "F.Cu")
		(at 97.663 -240.538 -90)
		(property "Reference" "SC435"
			(at 0 0 270)
			(layer "F.SilkS")
			(hide yes)
			(effects
				(font
					(size 1.27 1.27)
				)
			)
		)
		(property "Value" "SCD1U16V2KX-3GP"
			(at 1.1811 -2.7051 270)
			(unlocked yes)
			(layer "F.Fab")
			(hide yes)
			(effects
				(font
					(size 1.016 1.016)
					(thickness 0.1524)
				)
			)
		)
		(property "Device Type" "C402H22"
			(at 1.1811 -4.2291 270)
			(unlocked yes)
			(layer "F.Fab")
			(hide yes)
			(effects
				(font
					(size 1.016 1.016)
					(thickness 0.1524)
				)
			)
		)
		(duplicate_pad_numbers_are_jumpers no)
		(fp_rect
			(start -0.4318 0.9525)
			(end 0.4318 -0.9525)
			(stroke
				(width 0)
				(type default)
			)
			(fill no)
			(layer "F.CrtYd")
		)
		(fp_rect
			(start -0.4318 0.9525)
			(end 0.4318 -0.9525)
			(stroke
				(width 0)
				(type default)
			)
			(fill no)
			(layer "F.Fab")
		)
		(pad "1" smd custom
			(at 0 -0.4445 270)
			(size 0.1524 0.1524)
			(layers "F.Cu" "F.Mask" "F.Paste")
			(net "P3V3_STBY")
			(options
				(clearance outline)
				(anchor circle)
			)
			(primitives
				(gr_poly
					(pts
						(arc
							(start 0.3048 -0.2032)
							(mid 0.275042 -0.275042)
							(end 0.2032 -0.3048)
						)
						(arc
							(start -0.2032 -0.3048)
							(mid -0.275042 -0.275042)
							(end -0.3048 -0.2032)
						)
						(arc
							(start -0.3048 0.2032)
							(mid -0.275042 0.275042)
							(end -0.2032 0.3048)
						)
						(arc
							(start 0.2032 0.3048)
							(mid 0.275042 0.275042)
							(end 0.3048 0.2032)
						)
					)
					(width 0)
					(fill yes)
				)
			)
		)
		(pad "2" smd custom
			(at 0 0.4445 270)
			(size 0.1524 0.1524)
			(layers "F.Cu" "F.Mask" "F.Paste")
			(net "GND")
			(options
				(clearance outline)
				(anchor circle)
			)
			(primitives
				(gr_poly
					(pts
						(arc
							(start 0.3048 -0.2032)
							(mid 0.275042 -0.275042)
							(end 0.2032 -0.3048)
						)
						(arc
							(start -0.2032 -0.3048)
							(mid -0.275042 -0.275042)
							(end -0.3048 -0.2032)
						)
						(arc
							(start -0.3048 0.2032)
							(mid -0.275042 0.275042)
							(end -0.2032 0.3048)
						)
						(arc
							(start 0.2032 0.3048)
							(mid 0.275042 0.275042)
							(end 0.3048 0.2032)
						)
					)
					(width 0)
					(fill yes)
				)
			)
		)
	)
)
